(kicad_pcb
	(version 20260206)
	(generator "pcbnew")
	(generator_version "10.0")
	(general
		(thickness 1.6)
		(legacy_teardrops no)
	)
	(paper "A4")
	(title_block
		(title "Bryce Canyon_R.DPB_16317-1_OCP.brd")
		(comment 1 "Bryce Canyon / footprints 1483-1490 of 2099")
	)
	(layers
		(0 "F.Cu" signal "TOP")
		(4 "In1.Cu" signal "L2GND")
		(6 "In2.Cu" signal "L3")
		(8 "In3.Cu" signal "L4VCC")
		(10 "In4.Cu" signal "L5VCC")
		(12 "In5.Cu" signal "L6")
		(14 "In6.Cu" signal "L7GND")
		(2 "B.Cu" signal "BOTTOM")
		(9 "F.Adhes" user "F.Adhesive")
		(11 "B.Adhes" user "B.Adhesive")
		(13 "F.Paste" user "Package Geometry/Pastemask Top")
		(15 "B.Paste" user "Package Geometry/Pastemask Bottom")
		(5 "F.SilkS" user "Ref Des/Silkscreen Top")
		(7 "B.SilkS" user "Ref Des/Silkscreen Bottom")
		(1 "F.Mask" user "Board Geometry/Soldermask Top")
		(3 "B.Mask" user "Board Geometry/Soldermask Bottom")
		(17 "Dwgs.User" user "User.Drawings")
		(19 "Cmts.User" user "User.Comments")
		(21 "Eco1.User" user "User.Eco1")
		(23 "Eco2.User" user "User.Eco2")
		(25 "Edge.Cuts" user "Board Geometry/Outline")
		(27 "Margin" user)
		(31 "F.CrtYd" user "Package Geometry/Place Bound Top")
		(29 "B.CrtYd" user "Package Geometry/Place Bound Bottom")
		(35 "F.Fab" user "Ref Des/Assembly Top")
		(33 "B.Fab" user "Ref Des/Assembly Bottom")
	)
	(footprint ""
		(layer "F.Cu")
		(at 21.480018 -99.401884)
		(property "Reference" "R387"
			(at 0 0 0)
			(layer "F.SilkS")
			(hide yes)
			(effects
				(font
					(size 1.27 1.27)
				)
			)
		)
		(property "Value" "91R3F-1-GP"
			(at -0.0254 -2.5146 0)
			(unlocked yes)
			(layer "F.Fab")
			(hide yes)
			(effects
				(font
					(size 1.016 1.016)
					(thickness 0.1524)
				)
			)
		)
		(property "Device Type" "R603H22"
			(at -0.0254 -4.0386 0)
			(unlocked yes)
			(layer "F.Fab")
			(hide yes)
			(effects
				(font
					(size 1.016 1.016)
					(thickness 0.1524)
				)
			)
		)
		(duplicate_pad_numbers_are_jumpers no)
		(fp_line
			(start -0.4826 0)
			(end -0.2032 0)
			(stroke
				(width 0.2032)
				(type default)
			)
			(layer "F.SilkS")
		)
		(fp_line
			(start 0.2032 0)
			(end 0.4826 0)
			(stroke
				(width 0.2032)
				(type default)
			)
			(layer "F.SilkS")
		)
		(fp_rect
			(start -0.5842 1.3335)
			(end 0.5842 -1.3335)
			(stroke
				(width 0)
				(type default)
			)
			(fill no)
			(layer "F.CrtYd")
		)
		(fp_rect
			(start -0.5842 1.3335)
			(end 0.5842 -1.3335)
			(stroke
				(width 0)
				(type default)
			)
			(fill no)
			(layer "F.Fab")
		)
		(pad "1" smd custom
			(at 0 -0.762)
			(size 0.2159 0.2159)
			(layers "F.Cu" "F.Mask" "F.Paste")
			(net "P5V_B_1")
			(options
				(clearance outline)
				(anchor circle)
			)
			(primitives
				(gr_poly
					(pts
						(arc
							(start -0.3302 -0.4318)
							(mid -0.402042 -0.402042)
							(end -0.4318 -0.3302)
						)
						(arc
							(start -0.4318 0.3302)
							(mid -0.402042 0.402042)
							(end -0.3302 0.4318)
						)
						(arc
							(start 0.3302 0.4318)
							(mid 0.402042 0.402042)
							(end 0.4318 0.3302)
						)
						(arc
							(start 0.4318 -0.3302)
							(mid 0.402042 -0.402042)
							(end 0.3302 -0.4318)
						)
					)
					(width 0)
					(fill yes)
				)
			)
		)
		(pad "2" smd custom
			(at 0 0.762)
			(size 0.2159 0.2159)
			(layers "F.Cu" "F.Mask" "F.Paste")
			(net "DRV_ACT_12")
			(options
				(clearance outline)
				(anchor circle)
			)
			(primitives
				(gr_poly
					(pts
						(arc
							(start -0.3302 -0.4318)
							(mid -0.402042 -0.402042)
							(end -0.4318 -0.3302)
						)
						(arc
							(start -0.4318 0.3302)
							(mid -0.402042 0.402042)
							(end -0.3302 0.4318)
						)
						(arc
							(start 0.3302 0.4318)
							(mid 0.402042 0.402042)
							(end 0.4318 0.3302)
						)
						(arc
							(start 0.4318 -0.3302)
							(mid 0.402042 -0.402042)
							(end 0.3302 -0.4318)
						)
					)
					(width 0)
					(fill yes)
				)
			)
		)
	)
	(footprint ""
		(layer "F.Cu")
		(at 65.83553 -129.99085 90)
		(property "Reference" "VIA27"
			(at 0 0 90)
			(layer "F.SilkS")
			(hide yes)
			(effects
				(font
					(size 1.27 1.27)
				)
			)
		)
		(property "Value" "100OHM-8L-2D36MM-L18-GP"
			(at 3.8989 0.5715 90)
			(unlocked yes)
			(layer "F.Fab")
			(hide yes)
			(effects
				(font
					(size 1.016 1.016)
					(thickness 0.1524)
				)
			)
		)
		(property "Device Type" "VIA-PCIE-4P-414097"
			(at 3.8989 -0.9525 90)
			(unlocked yes)
			(layer "F.Fab")
			(hide yes)
			(effects
				(font
					(size 1.016 1.016)
					(thickness 0.1524)
				)
			)
		)
		(duplicate_pad_numbers_are_jumpers no)
		(fp_rect
			(start -2.0701 0.4826)
			(end 2.0701 -0.4826)
			(stroke
				(width 0)
				(type default)
			)
			(fill no)
			(layer "F.CrtYd")
		)
		(fp_rect
			(start -2.0701 0.4826)
			(end 2.0701 -0.4826)
			(stroke
				(width 0)
				(type default)
			)
			(fill no)
			(layer "F.Fab")
		)
		(pad "1" thru_hole circle
			(at -1.5875 0 90)
			(size 0.508 0.508)
			(drill 0.254)
			(layers "*.Cu" "*.Mask")
			(remove_unused_layers no)
			(net "GND")
			(clearance 0.2286)
			(thermal_gap 0.2286)
		)
		(pad "2" thru_hole circle
			(at -0.5715 0 90)
			(size 0.508 0.508)
			(drill 0.254)
			(layers "*.Cu" "*.Mask")
			(remove_unused_layers no)
			(net "PHY_SCC_B_TO_DRV_B_13_DP")
			(clearance 0.2286)
			(thermal_gap 0.2286)
		)
		(pad "3" thru_hole circle
			(at 0.5715 0 90)
			(size 0.508 0.508)
			(drill 0.254)
			(layers "*.Cu" "*.Mask")
			(remove_unused_layers no)
			(net "PHY_SCC_B_TO_DRV_B_13_DN")
			(clearance 0.2286)
			(thermal_gap 0.2286)
		)
		(pad "4" thru_hole circle
			(at 1.5875 0 90)
			(size 0.508 0.508)
			(drill 0.254)
			(layers "*.Cu" "*.Mask")
			(remove_unused_layers no)
			(net "GND")
			(clearance 0.2286)
			(thermal_gap 0.2286)
		)
	)
	(footprint ""
		(layer "F.Cu")
		(at 146.685 -249.555 180)
		(property "Reference" "Q15"
			(at 0 0 180)
			(layer "F.SilkS")
			(hide yes)
			(effects
				(font
					(size 1.27 1.27)
				)
			)
		)
		(property "Value" "2N7002KDW-GP"
			(at -2.3622 -8.2042 180)
			(unlocked yes)
			(layer "F.Fab")
			(hide yes)
			(effects
				(font
					(size 1.016 1.016)
					(thickness 0.1524)
				)
			)
		)
		(property "Device Type" "SOT-363H44"
			(at -2.3622 -10.1092 180)
			(unlocked yes)
			(layer "F.Fab")
			(hide yes)
			(effects
				(font
					(size 1.016 1.016)
					(thickness 0.1524)
				)
			)
		)
		(duplicate_pad_numbers_are_jumpers no)
		(fp_line
			(start 1.4478 1.7018)
			(end 1.4478 -1.7018)
			(stroke
				(width 0.1524)
				(type default)
			)
			(layer "F.SilkS")
		)
		(fp_line
			(start 1.4478 -1.7018)
			(end -1.4478 -1.7018)
			(stroke
				(width 0.1524)
				(type default)
			)
			(layer "F.SilkS")
		)
		(fp_line
			(start -1.27 1.524)
			(end -1.27 0.6604)
			(stroke
				(width 0.4826)
				(type default)
			)
			(layer "F.SilkS")
		)
		(fp_line
			(start -1.4478 1.7018)
			(end 1.4478 1.7018)
			(stroke
				(width 0.1524)
				(type default)
			)
			(layer "F.SilkS")
		)
		(fp_line
			(start -1.4478 -1.7018)
			(end -1.4478 1.7018)
			(stroke
				(width 0.1524)
				(type default)
			)
			(layer "F.SilkS")
		)
		(fp_poly
			(pts
				(xy -1.524 -1.778) (xy 1.524 -1.778) (xy 1.524 1.778) (xy -1.524 1.778)
			)
			(stroke
				(width 0)
				(type default)
			)
			(fill no)
			(layer "F.CrtYd")
		)
		(fp_poly
			(pts
				(xy -1.524 -1.778) (xy 1.524 -1.778) (xy 1.524 1.778) (xy -1.524 1.778)
			)
			(stroke
				(width 0)
				(type default)
			)
			(fill no)
			(layer "F.Fab")
		)
		(pad "1" smd rect
			(at -0.65024 0.9398 180)
			(size 0.4064 1.016)
			(layers "F.Cu" "F.Mask" "F.Paste")
			(net "GND")
		)
		(pad "2" smd rect
			(at 0 0.9398 180)
			(size 0.4064 1.016)
			(layers "F.Cu" "F.Mask" "F.Paste")
			(net "SW_PWR_R_HDD4")
		)
		(pad "3" smd rect
			(at 0.65024 0.9398 180)
			(size 0.4064 1.016)
			(layers "F.Cu" "F.Mask" "F.Paste")
			(net "SW_HDD_P4")
		)
		(pad "4" smd rect
			(at 0.65024 -0.9398 180)
			(size 0.4064 1.016)
			(layers "F.Cu" "F.Mask" "F.Paste")
			(net "GND")
		)
		(pad "5" smd rect
			(at 0 -0.9398 180)
			(size 0.4064 1.016)
			(layers "F.Cu" "F.Mask" "F.Paste")
			(net "SW_HDD_G4")
		)
		(pad "6" smd rect
			(at -0.65024 -0.9398 180)
			(size 0.4064 1.016)
			(layers "F.Cu" "F.Mask" "F.Paste")
			(net "SW_HDD_R4")
		)
	)
	(footprint ""
		(layer "F.Cu")
		(at 394.589 -32.004 -90)
		(property "Reference" "R805"
			(at 0 0 270)
			(layer "F.SilkS")
			(hide yes)
			(effects
				(font
					(size 1.27 1.27)
				)
			)
		)
		(property "Value" "2R6F-GP"
			(at -0.0508 -4.8514 270)
			(unlocked yes)
			(layer "F.Fab")
			(hide yes)
			(effects
				(font
					(size 1.016 1.016)
					(thickness 0.1524)
				)
			)
		)
		(property "Device Type" "R1206H26"
			(at 0 -6.3754 270)
			(unlocked yes)
			(layer "F.Fab")
			(hide yes)
			(effects
				(font
					(size 1.016 1.016)
					(thickness 0.1524)
				)
			)
		)
		(duplicate_pad_numbers_are_jumpers no)
		(fp_line
			(start -1.016 2.2352)
			(end -1.016 -2.2352)
			(stroke
				(width 0.1524)
				(type default)
			)
			(layer "F.SilkS")
		)
		(fp_line
			(start 1.016 2.2352)
			(end -1.016 2.2352)
			(stroke
				(width 0.1524)
				(type default)
			)
			(layer "F.SilkS")
		)
		(fp_line
			(start -1.016 -2.2352)
			(end 1.016 -2.2352)
			(stroke
				(width 0.1524)
				(type default)
			)
			(layer "F.SilkS")
		)
		(fp_line
			(start 1.016 -2.2352)
			(end 1.016 2.2352)
			(stroke
				(width 0.1524)
				(type default)
			)
			(layer "F.SilkS")
		)
		(fp_rect
			(start -1.0922 2.3114)
			(end 1.0922 -2.3114)
			(stroke
				(width 0)
				(type default)
			)
			(fill no)
			(layer "F.CrtYd")
		)
		(fp_poly
			(pts
				(xy -1.0922 -2.3114) (xy 1.0922 -2.3114) (xy 1.0922 2.3114) (xy -1.0922 2.3114)
			)
			(stroke
				(width 0)
				(type default)
			)
			(fill no)
			(layer "F.Fab")
		)
		(pad "1" smd rect
			(at 0 -1.397 270)
			(size 1.651 1.27)
			(layers "F.Cu" "F.Mask" "F.Paste")
			(net "P5V_HDD32")
		)
		(pad "2" smd rect
			(at 0 1.397 270)
			(size 1.651 1.27)
			(layers "F.Cu" "F.Mask" "F.Paste")
			(net "5V_PRE_32")
		)
	)
	(footprint ""
		(layer "F.Cu")
		(at 111.506 -247.65 180)
		(property "Reference" "D3"
			(at 0 0 180)
			(layer "F.SilkS")
			(hide yes)
			(effects
				(font
					(size 1.27 1.27)
				)
			)
		)
		(property "Value" "RB551V30-GP"
			(at 0 -6.7818 180)
			(unlocked yes)
			(layer "F.Fab")
			(hide yes)
			(effects
				(font
					(size 1.016 1.016)
					(thickness 0.1524)
				)
			)
		)
		(property "Device Type" "SOD323AKH38"
			(at 0 -8.6868 180)
			(unlocked yes)
			(layer "F.Fab")
			(hide yes)
			(effects
				(font
					(size 1.016 1.016)
					(thickness 0.1524)
				)
			)
		)
		(duplicate_pad_numbers_are_jumpers no)
		(fp_line
			(start 0.889 2.159)
			(end -0.889 2.159)
			(stroke
				(width 0.1524)
				(type default)
			)
			(layer "F.SilkS")
		)
		(fp_line
			(start 0.889 -1.9304)
			(end 0.889 2.159)
			(stroke
				(width 0.1524)
				(type default)
			)
			(layer "F.SilkS")
		)
		(fp_line
			(start 0.762 2.0574)
			(end -0.762 2.0574)
			(stroke
				(width 0.508)
				(type default)
			)
			(layer "F.SilkS")
		)
		(fp_line
			(start -0.889 2.159)
			(end -0.889 -1.9304)
			(stroke
				(width 0.1524)
				(type default)
			)
			(layer "F.SilkS")
		)
		(fp_line
			(start -0.889 -1.9304)
			(end 0.889 -1.9304)
			(stroke
				(width 0.1524)
				(type default)
			)
			(layer "F.SilkS")
		)
		(fp_rect
			(start -1.016 2.3114)
			(end 1.016 -2.0066)
			(stroke
				(width 0)
				(type default)
			)
			(fill no)
			(layer "F.CrtYd")
		)
		(fp_poly
			(pts
				(xy -1.016 -2.0066) (xy 1.016 -2.0066) (xy 1.016 2.3114) (xy -1.016 2.3114)
			)
			(stroke
				(width 0)
				(type default)
			)
			(fill no)
			(layer "F.Fab")
		)
		(pad "A" smd rect
			(at 0 -1.143 180)
			(size 0.5588 1.016)
			(layers "F.Cu" "F.Mask" "F.Paste")
			(net "SW_HDD_R3")
		)
		(pad "K" smd rect
			(at 0 1.143 180)
			(size 0.5588 1.016)
			(layers "F.Cu" "F.Mask" "F.Paste")
			(net "SW_HDD_N3")
		)
	)
	(footprint ""
		(layer "F.Cu")
		(at 83.3374 -33.782 -90)
		(property "Reference" "C368"
			(at 0 0 270)
			(layer "F.SilkS")
			(hide yes)
			(effects
				(font
					(size 1.27 1.27)
				)
			)
		)
		(property "Value" "SC1U16V3KX-5GP"
			(at 0 -2.8194 270)
			(unlocked yes)
			(layer "F.Fab")
			(hide yes)
			(effects
				(font
					(size 1.016 1.016)
					(thickness 0.1524)
				)
			)
		)
		(property "Device Type" "C603H36"
			(at 0 -4.3434 270)
			(unlocked yes)
			(layer "F.Fab")
			(hide yes)
			(effects
				(font
					(size 1.016 1.016)
					(thickness 0.1524)
				)
			)
		)
		(duplicate_pad_numbers_are_jumpers no)
		(fp_line
			(start 0.508 0)
			(end -0.508 0)
			(stroke
				(width 0.2032)
				(type default)
			)
			(layer "F.SilkS")
		)
		(fp_rect
			(start -0.5842 1.3335)
			(end 0.5842 -1.3335)
			(stroke
				(width 0)
				(type default)
			)
			(fill no)
			(layer "F.CrtYd")
		)
		(fp_rect
			(start -0.5842 1.3335)
			(end 0.5842 -1.3335)
			(stroke
				(width 0)
				(type default)
			)
			(fill no)
			(layer "F.Fab")
		)
		(pad "1" smd custom
			(at 0 -0.762 270)
			(size 0.2159 0.2159)
			(layers "F.Cu" "F.Mask" "F.Paste")
			(net "P5V_HDD26")
			(options
				(clearance outline)
				(anchor circle)
			)
			(primitives
				(gr_poly
					(pts
						(arc
							(start -0.3302 -0.4318)
							(mid -0.402042 -0.402042)
							(end -0.4318 -0.3302)
						)
						(arc
							(start -0.4318 0.3302)
							(mid -0.402042 0.402042)
							(end -0.3302 0.4318)
						)
						(arc
							(start 0.3302 0.4318)
							(mid 0.402042 0.402042)
							(end 0.4318 0.3302)
						)
						(arc
							(start 0.4318 -0.3302)
							(mid 0.402042 -0.402042)
							(end 0.3302 -0.4318)
						)
					)
					(width 0)
					(fill yes)
				)
			)
		)
		(pad "2" smd custom
			(at 0 0.762 270)
			(size 0.2159 0.2159)
			(layers "F.Cu" "F.Mask" "F.Paste")
			(net "GND")
			(options
				(clearance outline)
				(anchor circle)
			)
			(primitives
				(gr_poly
					(pts
						(arc
							(start -0.3302 -0.4318)
							(mid -0.402042 -0.402042)
							(end -0.4318 -0.3302)
						)
						(arc
							(start -0.4318 0.3302)
							(mid -0.402042 0.402042)
							(end -0.3302 0.4318)
						)
						(arc
							(start 0.3302 0.4318)
							(mid 0.402042 0.402042)
							(end 0.4318 0.3302)
						)
						(arc
							(start 0.4318 -0.3302)
							(mid 0.402042 -0.402042)
							(end 0.3302 -0.4318)
						)
					)
					(width 0)
					(fill yes)
				)
			)
		)
	)
	(footprint ""
		(layer "F.Cu")
		(at 469.519 -129.286 180)
		(property "Reference" "R609"
			(at 0 0 180)
			(layer "F.SilkS")
			(hide yes)
			(effects
				(font
					(size 1.27 1.27)
				)
			)
		)
		(property "Value" "0R2J-2-GP"
			(at 0.064008 -3.993896 180)
			(unlocked yes)
			(layer "F.Fab")
			(hide yes)
			(effects
				(font
					(size 1.016 1.016)
					(thickness 0.1524)
				)
			)
		)
		(property "Device Type" "R402H16"
			(at 0.064008 -5.517896 180)
			(unlocked yes)
			(layer "F.Fab")
			(hide yes)
			(effects
				(font
					(size 1.016 1.016)
					(thickness 0.1524)
				)
			)
		)
		(duplicate_pad_numbers_are_jumpers no)
		(fp_line
			(start 0.508 -0.9398)
			(end -0.508 -0.9398)
			(stroke
				(width 0.1524)
				(type default)
			)
			(layer "F.SilkS")
		)
		(fp_line
			(start -0.508 -0.9398)
			(end -0.508 0.9398)
			(stroke
				(width 0.1524)
				(type default)
			)
			(layer "F.SilkS")
		)
		(fp_rect
			(start -0.508 0.9398)
			(end 0.508 -0.9398)
			(stroke
				(width 0)
				(type default)
			)
			(fill no)
			(layer "F.CrtYd")
		)
		(fp_rect
			(start -0.508 0.9398)
			(end 0.508 -0.9398)
			(stroke
				(width 0)
				(type default)
			)
			(fill no)
			(layer "F.Fab")
		)
		(pad "1" smd custom
			(at 0 -0.4445 180)
			(size 0.1397 0.1397)
			(layers "F.Cu" "F.Mask" "F.Paste")
			(net "DRIVE_B_23_PWR")
			(options
				(clearance outline)
				(anchor circle)
			)
			(primitives
				(gr_poly
					(pts
						(arc
							(start -0.1778 -0.2794)
							(mid -0.249642 -0.249642)
							(end -0.2794 -0.1778)
						)
						(arc
							(start -0.2794 0.1778)
							(mid -0.249642 0.249642)
							(end -0.1778 0.2794)
						)
						(arc
							(start 0.1778 0.2794)
							(mid 0.249642 0.249642)
							(end 0.2794 0.1778)
						)
						(arc
							(start 0.2794 -0.1778)
							(mid 0.249642 -0.249642)
							(end 0.1778 -0.2794)
						)
					)
					(width 0)
					(fill yes)
				)
			)
		)
		(pad "2" smd custom
			(at 0 0.4445 180)
			(size 0.1397 0.1397)
			(layers "F.Cu" "F.Mask" "F.Paste")
			(net "SW_PWR_R_HDD23")
			(options
				(clearance outline)
				(anchor circle)
			)
			(primitives
				(gr_poly
					(pts
						(arc
							(start -0.1778 -0.2794)
							(mid -0.249642 -0.249642)
							(end -0.2794 -0.1778)
						)
						(arc
							(start -0.2794 0.1778)
							(mid -0.249642 0.249642)
							(end -0.1778 0.2794)
						)
						(arc
							(start 0.1778 0.2794)
							(mid 0.249642 0.249642)
							(end 0.2794 0.1778)
						)
						(arc
							(start 0.2794 -0.1778)
							(mid 0.249642 -0.249642)
							(end 0.1778 -0.2794)
						)
					)
					(width 0)
					(fill yes)
				)
			)
		)
	)
	(footprint ""
		(layer "F.Cu")
		(at 52.578 -19.177 180)
		(property "Reference" "R657"
			(at 0 0 180)
			(layer "F.SilkS")
			(hide yes)
			(effects
				(font
					(size 1.27 1.27)
				)
			)
		)
		(property "Value" "4K7R2F-GP"
			(at 0.064008 -3.993896 180)
			(unlocked yes)
			(layer "F.Fab")
			(hide yes)
			(effects
				(font
					(size 1.016 1.016)
					(thickness 0.1524)
				)
			)
		)
		(property "Device Type" "R402H16"
			(at 0.064008 -5.517896 180)
			(unlocked yes)
			(layer "F.Fab")
			(hide yes)
			(effects
				(font
					(size 1.016 1.016)
					(thickness 0.1524)
				)
			)
		)
		(duplicate_pad_numbers_are_jumpers no)
		(fp_line
			(start 0.508 -0.9398)
			(end -0.508 -0.9398)
			(stroke
				(width 0.1524)
				(type default)
			)
			(layer "F.SilkS")
		)
		(fp_line
			(start -0.508 -0.9398)
			(end -0.508 0.9398)
			(stroke
				(width 0.1524)
				(type default)
			)
			(layer "F.SilkS")
		)
		(fp_rect
			(start -0.508 0.9398)
			(end 0.508 -0.9398)
			(stroke
				(width 0)
				(type default)
			)
			(fill no)
			(layer "F.CrtYd")
		)
		(fp_rect
			(start -0.508 0.9398)
			(end 0.508 -0.9398)
			(stroke
				(width 0)
				(type default)
			)
			(fill no)
			(layer "F.Fab")
		)
		(pad "1" smd custom
			(at 0 -0.4445 180)
			(size 0.1397 0.1397)
			(layers "F.Cu" "F.Mask" "F.Paste")
			(net "SW_PWR_R_HDD25")
			(options
				(clearance outline)
				(anchor circle)
			)
			(primitives
				(gr_poly
					(pts
						(arc
							(start -0.1778 -0.2794)
							(mid -0.249642 -0.249642)
							(end -0.2794 -0.1778)
						)
						(arc
							(start -0.2794 0.1778)
							(mid -0.249642 0.249642)
							(end -0.1778 0.2794)
						)
						(arc
							(start 0.1778 0.2794)
							(mid 0.249642 0.249642)
							(end 0.2794 0.1778)
						)
						(arc
							(start 0.2794 -0.1778)
							(mid 0.249642 -0.249642)
							(end 0.1778 -0.2794)
						)
					)
					(width 0)
					(fill yes)
				)
			)
		)
		(pad "2" smd custom
			(at 0 0.4445 180)
			(size 0.1397 0.1397)
			(layers "F.Cu" "F.Mask" "F.Paste")
			(net "GND")
			(options
				(clearance outline)
				(anchor circle)
			)
			(primitives
				(gr_poly
					(pts
						(arc
							(start -0.1778 -0.2794)
							(mid -0.249642 -0.249642)
							(end -0.2794 -0.1778)
						)
						(arc
							(start -0.2794 0.1778)
							(mid -0.249642 0.249642)
							(end -0.1778 0.2794)
						)
						(arc
							(start 0.1778 0.2794)
							(mid 0.249642 0.249642)
							(end 0.2794 0.1778)
						)
						(arc
							(start 0.2794 -0.1778)
							(mid 0.249642 -0.249642)
							(end 0.1778 -0.2794)
						)
					)
					(width 0)
					(fill yes)
				)
			)
		)
	)
)
